(kicad_pcb
	(version 20260206)
	(generator "pcbnew")
	(generator_version "10.0")
	(general
		(thickness 1.6)
		(legacy_teardrops no)
	)
	(paper "A4")
	(title_block
		(title "03242023_DA0F0TMBIJ0_F0T_Motherboard_J_brd_V01_OCP.brd")
		(comment 1 "Grand Teton / footprints 1095-1099 of 6105")
	)
	(layers
		(0 "F.Cu" signal "TOP")
		(4 "In1.Cu" signal "GND")
		(6 "In2.Cu" signal "IN1")
		(8 "In3.Cu" signal "GND1")
		(10 "In4.Cu" signal "IN2")
		(12 "In5.Cu" signal "GND2")
		(14 "In6.Cu" signal "IN3")
		(16 "In7.Cu" signal "GND3")
		(18 "In8.Cu" signal "VCC")
		(20 "In9.Cu" signal "VCC1")
		(22 "In10.Cu" signal "GND4")
		(24 "In11.Cu" signal "IN4")
		(26 "In12.Cu" signal "GND5")
		(28 "In13.Cu" signal "IN5")
		(30 "In14.Cu" signal "GND6")
		(32 "In15.Cu" signal "IN6")
		(34 "In16.Cu" signal "GND7")
		(2 "B.Cu" signal "BOTTOM")
		(9 "F.Adhes" user "F.Adhesive")
		(11 "B.Adhes" user "B.Adhesive")
		(13 "F.Paste" user "Package Geometry/Pastemask Top")
		(15 "B.Paste" user "Package Geometry/Pastemask Bottom")
		(5 "F.SilkS" user "Ref Des/Silkscreen Top")
		(7 "B.SilkS" user "Ref Des/Silkscreen Bottom")
		(1 "F.Mask" user "Board Geometry/Soldermask Top")
		(3 "B.Mask" user "Board Geometry/Soldermask Bottom")
		(17 "Dwgs.User" user "User.Drawings")
		(19 "Cmts.User" user "User.Comments")
		(21 "Eco1.User" user "User.Eco1")
		(23 "Eco2.User" user "User.Eco2")
		(25 "Edge.Cuts" user "Board Geometry/Outline")
		(27 "Margin" user)
		(31 "F.CrtYd" user "Package Geometry/Place Bound Top")
		(29 "B.CrtYd" user "Package Geometry/Place Bound Bottom")
		(35 "F.Fab" user "Ref Des/Assembly Top")
		(33 "B.Fab" user "Ref Des/Assembly Bottom")
	)
	(footprint ""
		(layer "F.Cu")
		(at 358.64546 -407.233628)
		(property "Reference" "U316"
			(at -2.84988 -2.53873 0)
			(unlocked yes)
			(layer "F.SilkS")
			(effects
				(font
					(size 0.7874 0.5842)
					(thickness 0.1524)
				)
				(justify left)
			)
		)
		(property "Value" ""
			(at 0 0 0)
			(layer "F.Fab")
			(effects
				(font
					(size 1.27 1.27)
				)
			)
		)
		(duplicate_pad_numbers_are_jumpers no)
		(fp_line
			(start -1.38176 -1.100074)
			(end -1.38176 1.100074)
			(stroke
				(width 0.1524)
				(type default)
			)
			(layer "F.SilkS")
		)
		(fp_line
			(start -1.38176 1.100074)
			(end 1.38176 1.100074)
			(stroke
				(width 0.1524)
				(type default)
			)
			(layer "F.SilkS")
		)
		(fp_line
			(start -0.592074 -1.100074)
			(end -1.38176 -1.100074)
			(stroke
				(width 0.1524)
				(type default)
			)
			(layer "F.SilkS")
		)
		(fp_line
			(start 0 -0.508)
			(end -0.592074 -1.100074)
			(stroke
				(width 0.1524)
				(type default)
			)
			(layer "F.SilkS")
		)
		(fp_line
			(start 0.592074 -1.100074)
			(end 0 -0.508)
			(stroke
				(width 0.1524)
				(type default)
			)
			(layer "F.SilkS")
		)
		(fp_line
			(start 1.38176 -1.100074)
			(end 0.592074 -1.100074)
			(stroke
				(width 0.1524)
				(type default)
			)
			(layer "F.SilkS")
		)
		(fp_line
			(start 1.38176 1.100074)
			(end 1.38176 -1.100074)
			(stroke
				(width 0.1524)
				(type default)
			)
			(layer "F.SilkS")
		)
		(fp_poly
			(pts
				(xy -1.50241 -0.649986) (xy -1.9431 -0.429768) (xy -1.9431 -0.870204)
			)
			(stroke
				(width 0)
				(type default)
			)
			(fill yes)
			(layer "F.SilkS")
		)
		(fp_line
			(start -1.100074 -0.8001)
			(end -0.670052 -0.8001)
			(stroke
				(width 0.1)
				(type default)
			)
			(layer "F.Fab")
		)
		(fp_line
			(start -1.100074 0.8001)
			(end -1.100074 -0.8001)
			(stroke
				(width 0.1)
				(type default)
			)
			(layer "F.Fab")
		)
		(fp_line
			(start -0.670052 -1.100074)
			(end 0.670052 -1.100074)
			(stroke
				(width 0.1)
				(type default)
			)
			(layer "F.Fab")
		)
		(fp_line
			(start -0.670052 -0.8001)
			(end -0.670052 -1.100074)
			(stroke
				(width 0.1)
				(type default)
			)
			(layer "F.Fab")
		)
		(fp_line
			(start -0.670052 0.8001)
			(end -1.100074 0.8001)
			(stroke
				(width 0.1)
				(type default)
			)
			(layer "F.Fab")
		)
		(fp_line
			(start -0.670052 0.8001)
			(end -0.670052 -0.8001)
			(stroke
				(width 0.1)
				(type default)
			)
			(layer "F.Fab")
		)
		(fp_line
			(start -0.670052 1.100074)
			(end -0.670052 0.8001)
			(stroke
				(width 0.1)
				(type default)
			)
			(layer "F.Fab")
		)
		(fp_line
			(start 0.670052 -1.100074)
			(end 0.670052 -0.8001)
			(stroke
				(width 0.1)
				(type default)
			)
			(layer "F.Fab")
		)
		(fp_line
			(start 0.670052 -0.8001)
			(end 0.670052 0.8001)
			(stroke
				(width 0.1)
				(type default)
			)
			(layer "F.Fab")
		)
		(fp_line
			(start 0.670052 -0.8001)
			(end 1.100074 -0.8001)
			(stroke
				(width 0.1)
				(type default)
			)
			(layer "F.Fab")
		)
		(fp_line
			(start 0.670052 0.8001)
			(end 0.670052 1.100074)
			(stroke
				(width 0.1)
				(type default)
			)
			(layer "F.Fab")
		)
		(fp_line
			(start 0.670052 1.100074)
			(end -0.670052 1.100074)
			(stroke
				(width 0.1)
				(type default)
			)
			(layer "F.Fab")
		)
		(fp_line
			(start 1.100074 -0.8001)
			(end 1.100074 0.8001)
			(stroke
				(width 0.1)
				(type default)
			)
			(layer "F.Fab")
		)
		(fp_line
			(start 1.100074 0.8001)
			(end 0.670052 0.8001)
			(stroke
				(width 0.1)
				(type default)
			)
			(layer "F.Fab")
		)
		(fp_poly
			(pts
				(xy -1.524 -0.649986) (xy -2.286 -1.030986) (xy -2.286 -0.268986)
			)
			(stroke
				(width 0)
				(type default)
			)
			(fill yes)
			(layer "F.Fab")
		)
		(pad "1" smd rect
			(at -0.94996 -0.649986 270)
			(size 0.4064 0.508)
			(layers "F.Cu" "F.Mask" "F.Paste")
			(net "SWB_HSC_EN")
		)
		(pad "2" smd rect
			(at -0.94996 0 270)
			(size 0.4064 0.508)
			(layers "F.Cu" "F.Mask" "F.Paste")
			(net "GND")
		)
		(pad "3" smd rect
			(at -0.94996 0.649986 270)
			(size 0.4064 0.508)
			(layers "F.Cu" "F.Mask" "F.Paste")
			(net "GND")
		)
		(pad "4" smd rect
			(at 0.94996 0.649986 270)
			(size 0.4064 0.508)
			(layers "F.Cu" "F.Mask" "F.Paste")
			(net "NC_U316_2Y")
		)
		(pad "5" smd rect
			(at 0.94996 0 270)
			(size 0.4064 0.508)
			(layers "F.Cu" "F.Mask" "F.Paste")
			(net "P3V3_AUX")
		)
		(pad "6" smd rect
			(at 0.94996 -0.649986 270)
			(size 0.4064 0.508)
			(layers "F.Cu" "F.Mask" "F.Paste")
			(net "SWB_HSC_EN_BUF_R")
		)
	)
	(footprint ""
		(layer "F.Cu")
		(at 463.465926 -97.523808)
		(property "Reference" "R2473"
			(at 0 0 0)
			(layer "F.SilkS")
			(hide yes)
			(effects
				(font
					(size 1.27 1.27)
				)
			)
		)
		(property "Value" ""
			(at 0 0 0)
			(layer "F.Fab")
			(effects
				(font
					(size 1.27 1.27)
				)
			)
		)
		(duplicate_pad_numbers_are_jumpers no)
		(fp_line
			(start -0.7874 -0.4064)
			(end 0.7874 -0.4064)
			(stroke
				(width 0.1524)
				(type default)
			)
			(layer "F.SilkS")
		)
		(fp_line
			(start -0.7874 0.4064)
			(end -0.7874 -0.4064)
			(stroke
				(width 0.1524)
				(type default)
			)
			(layer "F.SilkS")
		)
		(fp_line
			(start 0.7874 -0.4064)
			(end 0.7874 0.4064)
			(stroke
				(width 0.1524)
				(type default)
			)
			(layer "F.SilkS")
		)
		(fp_line
			(start 0.7874 0.4064)
			(end -0.7874 0.4064)
			(stroke
				(width 0.1524)
				(type default)
			)
			(layer "F.SilkS")
		)
		(fp_line
			(start -0.67945 -0.305054)
			(end -0.12065 -0.305054)
			(stroke
				(width 0.1)
				(type default)
			)
			(layer "F.Fab")
		)
		(fp_line
			(start -0.67945 0.3048)
			(end -0.67945 -0.305054)
			(stroke
				(width 0.1)
				(type default)
			)
			(layer "F.Fab")
		)
		(fp_line
			(start -0.12065 -0.305054)
			(end -0.12065 -0.2794)
			(stroke
				(width 0.1)
				(type default)
			)
			(layer "F.Fab")
		)
		(fp_line
			(start -0.12065 -0.2794)
			(end 0.12065 -0.2794)
			(stroke
				(width 0.1)
				(type default)
			)
			(layer "F.Fab")
		)
		(fp_line
			(start -0.12065 0.2794)
			(end -0.12065 0.3048)
			(stroke
				(width 0.1)
				(type default)
			)
			(layer "F.Fab")
		)
		(fp_line
			(start -0.12065 0.3048)
			(end -0.67945 0.3048)
			(stroke
				(width 0.1)
				(type default)
			)
			(layer "F.Fab")
		)
		(fp_line
			(start 0.120396 0.2794)
			(end -0.12065 0.2794)
			(stroke
				(width 0.1)
				(type default)
			)
			(layer "F.Fab")
		)
		(fp_line
			(start 0.120396 0.3048)
			(end 0.120396 0.2794)
			(stroke
				(width 0.1)
				(type default)
			)
			(layer "F.Fab")
		)
		(fp_line
			(start 0.12065 -0.3048)
			(end 0.67945 -0.3048)
			(stroke
				(width 0.1)
				(type default)
			)
			(layer "F.Fab")
		)
		(fp_line
			(start 0.12065 -0.2794)
			(end 0.12065 -0.3048)
			(stroke
				(width 0.1)
				(type default)
			)
			(layer "F.Fab")
		)
		(fp_line
			(start 0.67945 -0.3048)
			(end 0.67945 0.3048)
			(stroke
				(width 0.1)
				(type default)
			)
			(layer "F.Fab")
		)
		(fp_line
			(start 0.67945 0.3048)
			(end 0.120396 0.3048)
			(stroke
				(width 0.1)
				(type default)
			)
			(layer "F.Fab")
		)
		(pad "1" smd circle
			(at -0.40005 0)
			(size 0 0)
			(layers "F.Cu" "F.Mask" "F.Paste")
			(net "FB_BMC_ISOLATE_R1")
		)
		(pad "2" smd circle
			(at 0.40005 0)
			(size 0 0)
			(layers "F.Cu" "F.Mask" "F.Paste")
			(net "FB_BMC_ISOLATE")
		)
	)
	(footprint ""
		(layer "F.Cu")
		(at 128.716278 -80.112616)
		(property "Reference" "R1380"
			(at 0 0 0)
			(layer "F.SilkS")
			(hide yes)
			(effects
				(font
					(size 1.27 1.27)
				)
			)
		)
		(property "Value" ""
			(at 0 0 0)
			(layer "F.Fab")
			(effects
				(font
					(size 1.27 1.27)
				)
			)
		)
		(duplicate_pad_numbers_are_jumpers no)
		(fp_line
			(start -0.7874 -0.4064)
			(end 0.7874 -0.4064)
			(stroke
				(width 0.1524)
				(type default)
			)
			(layer "F.SilkS")
		)
		(fp_line
			(start -0.7874 0.4064)
			(end -0.7874 -0.4064)
			(stroke
				(width 0.1524)
				(type default)
			)
			(layer "F.SilkS")
		)
		(fp_line
			(start 0.7874 -0.4064)
			(end 0.7874 0.4064)
			(stroke
				(width 0.1524)
				(type default)
			)
			(layer "F.SilkS")
		)
		(fp_line
			(start 0.7874 0.4064)
			(end -0.7874 0.4064)
			(stroke
				(width 0.1524)
				(type default)
			)
			(layer "F.SilkS")
		)
		(fp_line
			(start -0.67945 -0.305054)
			(end -0.12065 -0.305054)
			(stroke
				(width 0.1)
				(type default)
			)
			(layer "F.Fab")
		)
		(fp_line
			(start -0.67945 0.3048)
			(end -0.67945 -0.305054)
			(stroke
				(width 0.1)
				(type default)
			)
			(layer "F.Fab")
		)
		(fp_line
			(start -0.12065 -0.305054)
			(end -0.12065 -0.2794)
			(stroke
				(width 0.1)
				(type default)
			)
			(layer "F.Fab")
		)
		(fp_line
			(start -0.12065 -0.2794)
			(end 0.12065 -0.2794)
			(stroke
				(width 0.1)
				(type default)
			)
			(layer "F.Fab")
		)
		(fp_line
			(start -0.12065 0.2794)
			(end -0.12065 0.3048)
			(stroke
				(width 0.1)
				(type default)
			)
			(layer "F.Fab")
		)
		(fp_line
			(start -0.12065 0.3048)
			(end -0.67945 0.3048)
			(stroke
				(width 0.1)
				(type default)
			)
			(layer "F.Fab")
		)
		(fp_line
			(start 0.120396 0.2794)
			(end -0.12065 0.2794)
			(stroke
				(width 0.1)
				(type default)
			)
			(layer "F.Fab")
		)
		(fp_line
			(start 0.120396 0.3048)
			(end 0.120396 0.2794)
			(stroke
				(width 0.1)
				(type default)
			)
			(layer "F.Fab")
		)
		(fp_line
			(start 0.12065 -0.3048)
			(end 0.67945 -0.3048)
			(stroke
				(width 0.1)
				(type default)
			)
			(layer "F.Fab")
		)
		(fp_line
			(start 0.12065 -0.2794)
			(end 0.12065 -0.3048)
			(stroke
				(width 0.1)
				(type default)
			)
			(layer "F.Fab")
		)
		(fp_line
			(start 0.67945 -0.3048)
			(end 0.67945 0.3048)
			(stroke
				(width 0.1)
				(type default)
			)
			(layer "F.Fab")
		)
		(fp_line
			(start 0.67945 0.3048)
			(end 0.120396 0.3048)
			(stroke
				(width 0.1)
				(type default)
			)
			(layer "F.Fab")
		)
		(pad "1" smd circle
			(at -0.40005 0)
			(size 0 0)
			(layers "F.Cu" "F.Mask" "F.Paste")
			(net "P3V3_AUX")
		)
		(pad "2" smd circle
			(at 0.40005 0)
			(size 0 0)
			(layers "F.Cu" "F.Mask" "F.Paste")
			(net "JTAG_BMC_DBP_TDO")
		)
	)
	(footprint ""
		(layer "F.Cu")
		(at 18.640806 -396.810738 -90)
		(property "Reference" "C2351"
			(at 0 0 270)
			(layer "F.SilkS")
			(hide yes)
			(effects
				(font
					(size 1.27 1.27)
				)
			)
		)
		(property "Value" ""
			(at 0 0 270)
			(layer "F.Fab")
			(effects
				(font
					(size 1.27 1.27)
				)
			)
		)
		(duplicate_pad_numbers_are_jumpers no)
		(fp_line
			(start 0.7874 0.4064)
			(end -0.7874 0.4064)
			(stroke
				(width 0.1524)
				(type default)
			)
			(layer "F.SilkS")
		)
		(fp_line
			(start -0.7874 -0.4064)
			(end 0.001778 -0.4064)
			(stroke
				(width 0.1524)
				(type default)
			)
			(layer "F.SilkS")
		)
		(fp_line
			(start 0.7874 -0.4064)
			(end 0.7874 0.4064)
			(stroke
				(width 0.1524)
				(type default)
			)
			(layer "F.SilkS")
		)
		(fp_line
			(start -0.6858 0.3048)
			(end -0.6858 -0.3048)
			(stroke
				(width 0.1)
				(type default)
			)
			(layer "F.Fab")
		)
		(fp_line
			(start -0.1016 0.3048)
			(end -0.6858 0.3048)
			(stroke
				(width 0.1)
				(type default)
			)
			(layer "F.Fab")
		)
		(fp_line
			(start 0.1016 0.3048)
			(end 0.1016 0.2794)
			(stroke
				(width 0.1)
				(type default)
			)
			(layer "F.Fab")
		)
		(fp_line
			(start 0.6858 0.3048)
			(end 0.1016 0.3048)
			(stroke
				(width 0.1)
				(type default)
			)
			(layer "F.Fab")
		)
		(fp_line
			(start -0.1016 0.2794)
			(end -0.1016 0.3048)
			(stroke
				(width 0.1)
				(type default)
			)
			(layer "F.Fab")
		)
		(fp_line
			(start 0.1016 0.2794)
			(end -0.1016 0.2794)
			(stroke
				(width 0.1)
				(type default)
			)
			(layer "F.Fab")
		)
		(fp_line
			(start -0.1016 -0.2794)
			(end 0.1016 -0.2794)
			(stroke
				(width 0.1)
				(type default)
			)
			(layer "F.Fab")
		)
		(fp_line
			(start 0.1016 -0.2794)
			(end 0.1016 -0.3048)
			(stroke
				(width 0.1)
				(type default)
			)
			(layer "F.Fab")
		)
		(fp_line
			(start -0.6858 -0.3048)
			(end -0.1016 -0.3048)
			(stroke
				(width 0.1)
				(type default)
			)
			(layer "F.Fab")
		)
		(fp_line
			(start -0.1016 -0.3048)
			(end -0.1016 -0.2794)
			(stroke
				(width 0.1)
				(type default)
			)
			(layer "F.Fab")
		)
		(fp_line
			(start 0.1016 -0.3048)
			(end 0.6858 -0.3048)
			(stroke
				(width 0.1)
				(type default)
			)
			(layer "F.Fab")
		)
		(fp_line
			(start 0.6858 -0.3048)
			(end 0.6858 0.3048)
			(stroke
				(width 0.1)
				(type default)
			)
			(layer "F.Fab")
		)
		(pad "1" smd rect
			(at -0.40005 0 90)
			(size 0.4572 0.508)
			(layers "F.Cu" "F.Mask" "F.Paste")
			(net "P2E_MB_BMC_TX_BUF2_DP<0>")
		)
		(pad "2" smd rect
			(at 0.40005 0 90)
			(size 0.4572 0.508)
			(layers "F.Cu" "F.Mask" "F.Paste")
			(net "P2E_MB_BMC_TX_BUF_C_DP<0>")
		)
	)
	(footprint ""
		(layer "F.Cu")
		(at 312.443622 -34.102548 180)
		(property "Reference" "R1601"
			(at 0 0 180)
			(layer "F.SilkS")
			(hide yes)
			(effects
				(font
					(size 1.27 1.27)
				)
			)
		)
		(property "Value" ""
			(at 0 0 180)
			(layer "F.Fab")
			(effects
				(font
					(size 1.27 1.27)
				)
			)
		)
		(duplicate_pad_numbers_are_jumpers no)
		(fp_line
			(start 0.7874 0.4064)
			(end -0.7874 0.4064)
			(stroke
				(width 0.1524)
				(type default)
			)
			(layer "F.SilkS")
		)
		(fp_line
			(start 0.7874 -0.4064)
			(end 0.7874 0.4064)
			(stroke
				(width 0.1524)
				(type default)
			)
			(layer "F.SilkS")
		)
		(fp_line
			(start -0.7874 0.4064)
			(end -0.7874 -0.4064)
			(stroke
				(width 0.1524)
				(type default)
			)
			(layer "F.SilkS")
		)
		(fp_line
			(start -0.7874 -0.4064)
			(end 0.7874 -0.4064)
			(stroke
				(width 0.1524)
				(type default)
			)
			(layer "F.SilkS")
		)
		(fp_line
			(start 0.67945 0.3048)
			(end 0.120396 0.3048)
			(stroke
				(width 0.1)
				(type default)
			)
			(layer "F.Fab")
		)
		(fp_line
			(start 0.67945 -0.3048)
			(end 0.67945 0.3048)
			(stroke
				(width 0.1)
				(type default)
			)
			(layer "F.Fab")
		)
		(fp_line
			(start 0.12065 -0.2794)
			(end 0.12065 -0.3048)
			(stroke
				(width 0.1)
				(type default)
			)
			(layer "F.Fab")
		)
		(fp_line
			(start 0.12065 -0.3048)
			(end 0.67945 -0.3048)
			(stroke
				(width 0.1)
				(type default)
			)
			(layer "F.Fab")
		)
		(fp_line
			(start 0.120396 0.3048)
			(end 0.120396 0.2794)
			(stroke
				(width 0.1)
				(type default)
			)
			(layer "F.Fab")
		)
		(fp_line
			(start 0.120396 0.2794)
			(end -0.12065 0.2794)
			(stroke
				(width 0.1)
				(type default)
			)
			(layer "F.Fab")
		)
		(fp_line
			(start -0.12065 0.3048)
			(end -0.67945 0.3048)
			(stroke
				(width 0.1)
				(type default)
			)
			(layer "F.Fab")
		)
		(fp_line
			(start -0.12065 0.2794)
			(end -0.12065 0.3048)
			(stroke
				(width 0.1)
				(type default)
			)
			(layer "F.Fab")
		)
		(fp_line
			(start -0.12065 -0.2794)
			(end 0.12065 -0.2794)
			(stroke
				(width 0.1)
				(type default)
			)
			(layer "F.Fab")
		)
		(fp_line
			(start -0.12065 -0.305054)
			(end -0.12065 -0.2794)
			(stroke
				(width 0.1)
				(type default)
			)
			(layer "F.Fab")
		)
		(fp_line
			(start -0.67945 0.3048)
			(end -0.67945 -0.305054)
			(stroke
				(width 0.1)
				(type default)
			)
			(layer "F.Fab")
		)
		(fp_line
			(start -0.67945 -0.305054)
			(end -0.12065 -0.305054)
			(stroke
				(width 0.1)
				(type default)
			)
			(layer "F.Fab")
		)
		(pad "1" smd circle
			(at -0.40005 0 180)
			(size 0 0)
			(layers "F.Cu" "F.Mask" "F.Paste")
			(net "IRQ_SML0_ALERT_N")
		)
		(pad "2" smd circle
			(at 0.40005 0 180)
			(size 0 0)
			(layers "F.Cu" "F.Mask" "F.Paste")
			(net "P3V3_AUX")
		)
	)
)
